(kicad_pcb
	(version 20260206)
	(generator "pcbnew")
	(generator_version "10.0")
	(general
		(thickness 1.6)
		(legacy_teardrops no)
	)
	(paper "A4")
	(title_block
		(title "panther-plus-userver — 13130-1b_20150205.brd")
		(comment 1 "Honey Badger (Wiwynn) / footprints 587-588 of 1509")
	)
	(layers
		(0 "F.Cu" signal "TOP")
		(4 "In1.Cu" signal "L2")
		(6 "In2.Cu" signal "L3")
		(8 "In3.Cu" signal "L4")
		(10 "In4.Cu" signal "L5")
		(12 "In5.Cu" signal "L6")
		(14 "In6.Cu" signal "L7")
		(16 "In7.Cu" signal "L8")
		(18 "In8.Cu" signal "L9")
		(20 "In9.Cu" signal "L10")
		(22 "In10.Cu" signal "L11")
		(2 "B.Cu" signal "BOTTOM")
		(9 "F.Adhes" user "F.Adhesive")
		(11 "B.Adhes" user "B.Adhesive")
		(13 "F.Paste" user "Package Geometry/Pastemask Top")
		(15 "B.Paste" user "Package Geometry/Pastemask Bottom")
		(5 "F.SilkS" user "Ref Des/Silkscreen Top")
		(7 "B.SilkS" user "Ref Des/Silkscreen Bottom")
		(1 "F.Mask" user "Board Geometry/Soldermask Top")
		(3 "B.Mask" user "Board Geometry/Soldermask Bottom")
		(17 "Dwgs.User" user "User.Drawings")
		(19 "Cmts.User" user "User.Comments")
		(21 "Eco1.User" user "User.Eco1")
		(23 "Eco2.User" user "User.Eco2")
		(25 "Edge.Cuts" user "Board Geometry/Outline")
		(27 "Margin" user)
		(31 "F.CrtYd" user "Package Geometry/Place Bound Top")
		(29 "B.CrtYd" user "Package Geometry/Place Bound Bottom")
		(35 "F.Fab" user "Ref Des/Assembly Top")
		(33 "B.Fab" user "Ref Des/Assembly Bottom")
	)
	(footprint ""
		(layer "F.Cu")
		(at 69.342 -12.827 90)
		(property "Reference" "U42"
			(at 0 0 90)
			(layer "F.SilkS")
			(hide yes)
			(effects
				(font
					(size 1.27 1.27)
				)
			)
		)
		(property "Value" "SN74LVC1G11DCKR-GP"
			(at -4.897374 3.525266 90)
			(unlocked yes)
			(layer "F.Fab")
			(hide yes)
			(effects
				(font
					(size 1.016 1.016)
					(thickness 0.1524)
				)
			)
		)
		(property "Device Type" "UMT6H44"
			(at -4.897374 2.001266 90)
			(unlocked yes)
			(layer "F.Fab")
			(hide yes)
			(effects
				(font
					(size 1.016 1.016)
					(thickness 0.1524)
				)
			)
		)
		(duplicate_pad_numbers_are_jumpers no)
		(fp_line
			(start 1.0033 -0.3556)
			(end -1.0033 -0.3556)
			(stroke
				(width 0.1524)
				(type default)
			)
			(layer "F.SilkS")
		)
		(fp_line
			(start -1.0033 -0.3556)
			(end -1.0033 0.3556)
			(stroke
				(width 0.1524)
				(type default)
			)
			(layer "F.SilkS")
		)
		(fp_line
			(start -1.1557 0.2921)
			(end -1.1557 1.2954)
			(stroke
				(width 0.254)
				(type default)
			)
			(layer "F.SilkS")
		)
		(fp_line
			(start 1.0033 0.3556)
			(end 1.0033 -0.3556)
			(stroke
				(width 0.1524)
				(type default)
			)
			(layer "F.SilkS")
		)
		(fp_line
			(start -1.0033 0.3556)
			(end 1.0033 0.3556)
			(stroke
				(width 0.1524)
				(type default)
			)
			(layer "F.SilkS")
		)
		(fp_poly
			(pts
				(xy -1.016 0.3556) (xy 1.016 0.3556) (xy 1.016 -0.3556) (xy -1.016 -0.3556)
			)
			(stroke
				(width 0)
				(type default)
			)
			(fill yes)
			(layer "F.SilkS")
		)
		(fp_poly
			(pts
				(xy -1.0033 -0.8763) (xy -1.2573 -0.8763) (xy -1.2573 0.8763) (xy -0.9906 0.8763) (xy -0.9906 1.4097)
				(xy 0.9906 1.4097) (xy 0.9906 0.8763) (xy 1.2573 0.8763) (xy 1.2573 -0.8763) (xy 0.9906 -0.8763)
				(xy 0.9906 -1.4097) (xy -0.9906 -1.4097) (xy -0.9906 -0.8763)
			)
			(stroke
				(width 0)
				(type default)
			)
			(fill no)
			(layer "F.CrtYd")
		)
		(fp_poly
			(pts
				(xy -1.0033 -0.8763) (xy -1.2573 -0.8763) (xy -1.2573 0.8763) (xy -1.0033 0.8763) (xy -0.9906 0.8763)
				(xy -0.9906 1.4097) (xy 0.9906 1.4097) (xy 0.9906 0.8763) (xy 1.0033 0.8763) (xy 1.2573 0.8763)
				(xy 1.2573 -0.8763) (xy 1.0033 -0.8763) (xy 0.9906 -0.8763) (xy 0.9906 -1.4097) (xy -0.9906 -1.4097)
				(xy -0.9906 -0.8763)
			)
			(stroke
				(width 0)
				(type default)
			)
			(fill no)
			(layer "F.Fab")
		)
		(pad "1" smd rect
			(at -0.65024 0.94996 90)
			(size 0.4064 0.6604)
			(layers "F.Cu" "F.Mask" "F.Paste")
			(net "BMC_SYS_RESET#")
		)
		(pad "2" smd rect
			(at 0 0.94996 90)
			(size 0.4064 0.6604)
			(layers "F.Cu" "F.Mask" "F.Paste")
			(net "GND")
		)
		(pad "3" smd rect
			(at 0.65024 0.94996 90)
			(size 0.4064 0.6604)
			(layers "F.Cu" "F.Mask" "F.Paste")
			(net "HOST_LV_RSTBTN#")
		)
		(pad "4" smd rect
			(at 0.65024 -0.94996 90)
			(size 0.4064 0.6604)
			(layers "F.Cu" "F.Mask" "F.Paste")
			(net "PMU_RESETBUTTON#")
		)
		(pad "5" smd rect
			(at 0 -0.94996 90)
			(size 0.4064 0.6604)
			(layers "F.Cu" "F.Mask" "F.Paste")
			(net "P3V3")
		)
		(pad "6" smd rect
			(at -0.65024 -0.94996 90)
			(size 0.4064 0.6604)
			(layers "F.Cu" "F.Mask" "F.Paste")
			(net "XDP_RST_BTN_R#")
		)
	)
	(footprint ""
		(layer "F.Cu")
		(at 36.576 -27.305 90)
		(property "Reference" "CN4"
			(at 0 0 90)
			(layer "F.SilkS")
			(hide yes)
			(effects
				(font
					(size 1.27 1.27)
				)
			)
		)
		(property "Value" "SMC-CONN60A-GP"
			(at -0.7874 -13.1826 90)
			(unlocked yes)
			(layer "F.Fab")
			(hide yes)
			(effects
				(font
					(size 1.016 1.016)
					(thickness 0.1524)
				)
			)
		)
		(property "Device Type" "BSH-03001-FDA"
			(at -0.7874 -14.7066 90)
			(unlocked yes)
			(layer "F.Fab")
			(hide yes)
			(effects
				(font
					(size 1.016 1.016)
					(thickness 0.1524)
				)
			)
		)
		(duplicate_pad_numbers_are_jumpers no)
		(fp_line
			(start 10.1473 -1.4478)
			(end 10.9093 -0.6858)
			(stroke
				(width 0.3048)
				(type default)
			)
			(layer "F.SilkS")
		)
		(fp_line
			(start -10.9093 -0.6858)
			(end -10.1473 -1.4478)
			(stroke
				(width 0.3048)
				(type default)
			)
			(layer "F.SilkS")
		)
		(fp_poly
			(pts
				(xy -7.268464 6.785102) (xy -7.903464 7.420102) (xy -6.633464 7.420102)
			)
			(stroke
				(width 0)
				(type default)
			)
			(fill yes)
			(layer "F.SilkS")
		)
		(fp_rect
			(start -10.9093 6.7818)
			(end 10.9093 -1.4478)
			(stroke
				(width 0)
				(type default)
			)
			(fill no)
			(layer "F.CrtYd")
		)
		(fp_rect
			(start -10.9093 6.7818)
			(end 10.9093 -1.4478)
			(stroke
				(width 0)
				(type default)
			)
			(fill no)
			(layer "F.Fab")
		)
		(pad "" np_thru_hole circle
			(at -10.06475 0 90)
			(size 0.254 0.254)
			(drill 1.016)
			(layers "*.Cu" "*.Mask")
			(clearance 0.7366)
			(thermal_gap 0.7366)
		)
		(pad "" np_thru_hole circle
			(at 10.06475 0 90)
			(size 0.254 0.254)
			(drill 1.016)
			(layers "*.Cu" "*.Mask")
			(clearance 0.7366)
			(thermal_gap 0.7366)
		)
		(pad "1" smd rect
			(at -7.25043 5.52577 90)
			(size 0.2794 2.2606)
			(layers "F.Cu" "F.Mask" "F.Paste")
			(net "GND")
		)
		(pad "2" smd rect
			(at -7.25043 -0.19812 90)
			(size 0.2794 2.2606)
			(layers "F.Cu" "F.Mask" "F.Paste")
			(net "GND")
		)
		(pad "3" smd rect
			(at -6.75005 5.52577 90)
			(size 0.2794 2.2606)
			(layers "F.Cu" "F.Mask" "F.Paste")
			(net "XDP_CPU_PREQ#")
		)
		(pad "4" smd rect
			(at -6.75005 -0.19812 90)
			(size 0.2794 2.2606)
			(layers "F.Cu" "F.Mask" "F.Paste")
			(net "XDP_DFX_PORT_R_CLK0")
		)
		(pad "5" smd rect
			(at -6.24967 5.52577 90)
			(size 0.2794 2.2606)
			(layers "F.Cu" "F.Mask" "F.Paste")
			(net "XDP_CPU_PRDY#")
		)
		(pad "6" smd rect
			(at -6.24967 -0.19812 90)
			(size 0.2794 2.2606)
			(layers "F.Cu" "F.Mask" "F.Paste")
			(net "XDP_DFX_PORT_R_CLK1")
		)
		(pad "7" smd rect
			(at -5.75056 5.52577 90)
			(size 0.2794 2.2606)
			(layers "F.Cu" "F.Mask" "F.Paste")
			(net "GND")
		)
		(pad "8" smd rect
			(at -5.75056 -0.19812 90)
			(size 0.2794 2.2606)
			(layers "F.Cu" "F.Mask" "F.Paste")
			(net "GND")
		)
		(pad "9" smd rect
			(at -5.25018 5.52577 90)
			(size 0.2794 2.2606)
			(layers "F.Cu" "F.Mask" "F.Paste")
			(net "XDP_DFX_PORT0")
		)
		(pad "10" smd rect
			(at -5.25018 -0.19812 90)
			(size 0.2794 2.2606)
			(layers "F.Cu" "F.Mask" "F.Paste")
			(net "XDP_DFX_PORT8")
		)
		(pad "11" smd rect
			(at -4.7498 5.52577 90)
			(size 0.2794 2.2606)
			(layers "F.Cu" "F.Mask" "F.Paste")
			(net "XDP_DFX_PORT1")
		)
		(pad "12" smd rect
			(at -4.7498 -0.19812 90)
			(size 0.2794 2.2606)
			(layers "F.Cu" "F.Mask" "F.Paste")
			(net "XDP_DFX_PORT9")
		)
		(pad "13" smd rect
			(at -4.24942 5.52577 90)
			(size 0.2794 2.2606)
			(layers "F.Cu" "F.Mask" "F.Paste")
			(net "GND")
		)
		(pad "14" smd rect
			(at -4.24942 -0.19812 90)
			(size 0.2794 2.2606)
			(layers "F.Cu" "F.Mask" "F.Paste")
			(net "GND")
		)
		(pad "15" smd rect
			(at -3.75031 5.52577 90)
			(size 0.2794 2.2606)
			(layers "F.Cu" "F.Mask" "F.Paste")
			(net "XDP_DFX_PORT2")
		)
		(pad "16" smd rect
			(at -3.75031 -0.19812 90)
			(size 0.2794 2.2606)
			(layers "F.Cu" "F.Mask" "F.Paste")
			(net "XDP_DFX_PORT10")
		)
		(pad "17" smd rect
			(at -3.24993 5.52577 90)
			(size 0.2794 2.2606)
			(layers "F.Cu" "F.Mask" "F.Paste")
			(net "XDP_DFX_PORT3")
		)
		(pad "18" smd rect
			(at -3.24993 -0.19812 90)
			(size 0.2794 2.2606)
			(layers "F.Cu" "F.Mask" "F.Paste")
			(net "XDP_DFX_PORT11")
		)
		(pad "19" smd rect
			(at -2.74955 5.52577 90)
			(size 0.2794 2.2606)
			(layers "F.Cu" "F.Mask" "F.Paste")
			(net "GND")
		)
		(pad "20" smd rect
			(at -2.74955 -0.19812 90)
			(size 0.2794 2.2606)
			(layers "F.Cu" "F.Mask" "F.Paste")
			(net "GND")
		)
		(pad "21" smd rect
			(at -2.25044 5.52577 90)
			(size 0.2794 2.2606)
			(layers "F.Cu" "F.Mask" "F.Paste")
			(net "TP_XDP_DFX_PORT_CLK1")
		)
		(pad "22" smd rect
			(at -2.25044 -0.19812 90)
			(size 0.2794 2.2606)
			(layers "F.Cu" "F.Mask" "F.Paste")
			(net "Net_651")
		)
		(pad "23" smd rect
			(at -1.75006 5.52577 90)
			(size 0.2794 2.2606)
			(layers "F.Cu" "F.Mask" "F.Paste")
			(net "Net_649")
		)
		(pad "24" smd rect
			(at -1.75006 -0.19812 90)
			(size 0.2794 2.2606)
			(layers "F.Cu" "F.Mask" "F.Paste")
			(net "Net_650")
		)
		(pad "25" smd rect
			(at -1.24968 5.52577 90)
			(size 0.2794 2.2606)
			(layers "F.Cu" "F.Mask" "F.Paste")
			(net "GND")
		)
		(pad "26" smd rect
			(at -1.24968 -0.19812 90)
			(size 0.2794 2.2606)
			(layers "F.Cu" "F.Mask" "F.Paste")
			(net "GND")
		)
		(pad "27" smd rect
			(at -0.75057 5.52577 90)
			(size 0.2794 2.2606)
			(layers "F.Cu" "F.Mask" "F.Paste")
			(net "XDP_DFX_PORT4")
		)
		(pad "28" smd rect
			(at -0.75057 -0.19812 90)
			(size 0.2794 2.2606)
			(layers "F.Cu" "F.Mask" "F.Paste")
			(net "XDP_DFX_PORT12")
		)
		(pad "29" smd rect
			(at -0.25019 5.52577 90)
			(size 0.2794 2.2606)
			(layers "F.Cu" "F.Mask" "F.Paste")
			(net "XDP_DFX_PORT5")
		)
		(pad "30" smd rect
			(at -0.25019 -0.19812 90)
			(size 0.2794 2.2606)
			(layers "F.Cu" "F.Mask" "F.Paste")
			(net "XDP_DFX_PORT13")
		)
		(pad "31" smd rect
			(at 0.25019 5.52577 90)
			(size 0.2794 2.2606)
			(layers "F.Cu" "F.Mask" "F.Paste")
			(net "GND")
		)
		(pad "32" smd rect
			(at 0.25019 -0.19812 90)
			(size 0.2794 2.2606)
			(layers "F.Cu" "F.Mask" "F.Paste")
			(net "GND")
		)
		(pad "33" smd rect
			(at 0.75057 5.52577 90)
			(size 0.2794 2.2606)
			(layers "F.Cu" "F.Mask" "F.Paste")
			(net "XDP_DFX_PORT6")
		)
		(pad "34" smd rect
			(at 0.75057 -0.19812 90)
			(size 0.2794 2.2606)
			(layers "F.Cu" "F.Mask" "F.Paste")
			(net "XDP_DFX_PORT14")
		)
		(pad "35" smd rect
			(at 1.24968 5.52577 90)
			(size 0.2794 2.2606)
			(layers "F.Cu" "F.Mask" "F.Paste")
			(net "XDP_DFX_PORT7")
		)
		(pad "36" smd rect
			(at 1.24968 -0.19812 90)
			(size 0.2794 2.2606)
			(layers "F.Cu" "F.Mask" "F.Paste")
			(net "XDP_DFX_PORT15")
		)
		(pad "37" smd rect
			(at 1.75006 5.52577 90)
			(size 0.2794 2.2606)
			(layers "F.Cu" "F.Mask" "F.Paste")
			(net "GND")
		)
		(pad "38" smd rect
			(at 1.75006 -0.19812 90)
			(size 0.2794 2.2606)
			(layers "F.Cu" "F.Mask" "F.Paste")
			(net "GND")
		)
		(pad "39" smd rect
			(at 2.25044 5.52577 90)
			(size 0.2794 2.2606)
			(layers "F.Cu" "F.Mask" "F.Paste")
			(net "XDP_RSMRST_R#")
		)
		(pad "40" smd rect
			(at 2.25044 -0.19812 90)
			(size 0.2794 2.2606)
			(layers "F.Cu" "F.Mask" "F.Paste")
			(net "CLK_100M_XDP_R_DP")
		)
		(pad "41" smd rect
			(at 2.74955 5.52577 90)
			(size 0.2794 2.2606)
			(layers "F.Cu" "F.Mask" "F.Paste")
			(net "XDP_PWRBTN_R#")
		)
		(pad "42" smd rect
			(at 2.74955 -0.19812 90)
			(size 0.2794 2.2606)
			(layers "F.Cu" "F.Mask" "F.Paste")
			(net "CLK_100M_XDP_R_DN")
		)
		(pad "43" smd rect
			(at 3.24993 5.52577 90)
			(size 0.2794 2.2606)
			(layers "F.Cu" "F.Mask" "F.Paste")
			(net "P1V0")
		)
		(pad "44" smd rect
			(at 3.24993 -0.19812 90)
			(size 0.2794 2.2606)
			(layers "F.Cu" "F.Mask" "F.Paste")
			(net "VCC_OBS_CD")
		)
		(pad "45" smd rect
			(at 3.75031 5.52577 90)
			(size 0.2794 2.2606)
			(layers "F.Cu" "F.Mask" "F.Paste")
			(net "XDP_PWRGD_IN")
		)
		(pad "46" smd rect
			(at 3.75031 -0.19812 90)
			(size 0.2794 2.2606)
			(layers "F.Cu" "F.Mask" "F.Paste")
			(net "XDP_CPU_R_RESET#")
		)
		(pad "47" smd rect
			(at 4.24942 5.52577 90)
			(size 0.2794 2.2606)
			(layers "F.Cu" "F.Mask" "F.Paste")
			(net "XDP_RTEST#")
		)
		(pad "48" smd rect
			(at 4.24942 -0.19812 90)
			(size 0.2794 2.2606)
			(layers "F.Cu" "F.Mask" "F.Paste")
			(net "XDP_RST_BTN_R#")
		)
		(pad "49" smd rect
			(at 4.7498 5.52577 90)
			(size 0.2794 2.2606)
			(layers "F.Cu" "F.Mask" "F.Paste")
			(net "GND")
		)
		(pad "50" smd rect
			(at 4.7498 -0.19812 90)
			(size 0.2794 2.2606)
			(layers "F.Cu" "F.Mask" "F.Paste")
			(net "GND")
		)
		(pad "51" smd rect
			(at 5.25018 5.52577 90)
			(size 0.2794 2.2606)
			(layers "F.Cu" "F.Mask" "F.Paste")
			(net "SMB_XDP_DATA_R")
		)
		(pad "52" smd rect
			(at 5.25018 -0.19812 90)
			(size 0.2794 2.2606)
			(layers "F.Cu" "F.Mask" "F.Paste")
			(net "XDP_CPU_R_TDO")
		)
		(pad "53" smd rect
			(at 5.75056 5.52577 90)
			(size 0.2794 2.2606)
			(layers "F.Cu" "F.Mask" "F.Paste")
			(net "SMB_XDP_CLK_R")
		)
		(pad "54" smd rect
			(at 5.75056 -0.19812 90)
			(size 0.2794 2.2606)
			(layers "F.Cu" "F.Mask" "F.Paste")
			(net "XDP_SOC_CPU_TRST#")
		)
		(pad "55" smd rect
			(at 6.24967 5.52577 90)
			(size 0.2794 2.2606)
			(layers "F.Cu" "F.Mask" "F.Paste")
			(net "TP_XDP0_TCK1")
		)
		(pad "56" smd rect
			(at 6.24967 -0.19812 90)
			(size 0.2794 2.2606)
			(layers "F.Cu" "F.Mask" "F.Paste")
			(net "TDI_56")
		)
		(pad "57" smd rect
			(at 6.75005 5.52577 90)
			(size 0.2794 2.2606)
			(layers "F.Cu" "F.Mask" "F.Paste")
			(net "XDP_SOC_CPU_TCK")
		)
		(pad "58" smd rect
			(at 6.75005 -0.19812 90)
			(size 0.2794 2.2606)
			(layers "F.Cu" "F.Mask" "F.Paste")
			(net "XDP_SOC_CPU_TMS")
		)
		(pad "59" smd rect
			(at 7.25043 5.52577 90)
			(size 0.2794 2.2606)
			(layers "F.Cu" "F.Mask" "F.Paste")
			(net "GND")
		)
		(pad "60" smd rect
			(at 7.25043 -0.19812 90)
			(size 0.2794 2.2606)
			(layers "F.Cu" "F.Mask" "F.Paste")
			(net "XDP_P60")
		)
		(zone
			(layer "F.Cu")
			(hatch none 0.5)
			(connect_pads
				(clearance 0)
			)
			(min_thickness 0.25)
			(keepout
				(tracks allowed)
				(vias not_allowed)
				(pads allowed)
				(copperpour not_allowed)
				(footprints allowed)
			)
			(placement
				(enabled no)
				(sheetname "")
			)
			(fill
				(thermal_gap 0.5)
				(thermal_bridge_width 0.5)
				(island_removal_mode 0)
			)
			(polygon
				(pts
					(xy 37.50818 -19.91487) (xy 38.01618 -19.91487) (xy 38.01618 -34.69513) (xy 37.50818 -34.69513)
				)
			)
		)
		(zone
			(layer "F.Cu")
			(hatch none 0.5)
			(connect_pads
				(clearance 0)
			)
			(min_thickness 0.25)
			(keepout
				(tracks allowed)
				(vias not_allowed)
				(pads allowed)
				(copperpour not_allowed)
				(footprints allowed)
			)
			(placement
				(enabled no)
				(sheetname "")
			)
			(fill
				(thermal_gap 0.5)
				(thermal_bridge_width 0.5)
				(island_removal_mode 0)
			)
			(polygon
				(pts
					(xy 40.46347 -19.91487) (xy 40.97147 -19.91487) (xy 40.97147 -34.69513) (xy 40.46347 -34.69513)
				)
			)
		)
		(zone
			(layers "F.Cu" "B.Cu" "In1.Cu" "In2.Cu" "In3.Cu" "In4.Cu" "In5.Cu" "In6.Cu"
				"In7.Cu" "In8.Cu" "In9.Cu" "In10.Cu"
			)
			(hatch none 0.5)
			(connect_pads
				(clearance 0)
			)
			(min_thickness 0.25)
			(keepout
				(tracks not_allowed)
				(vias allowed)
				(pads allowed)
				(copperpour not_allowed)
				(footprints allowed)
			)
			(placement
				(enabled no)
				(sheetname "")
			)
			(fill
				(thermal_gap 0.5)
				(thermal_bridge_width 0.5)
				(island_removal_mode 0)
			)
			(polygon
				(pts
					(arc
						(start 37.3888 -37.36975)
						(mid 35.7632 -37.36975)
						(end 37.3888 -37.36975)
					)
				)
			)
		)
		(zone
			(layers "F.Cu" "B.Cu" "In1.Cu" "In2.Cu" "In3.Cu" "In4.Cu" "In5.Cu" "In6.Cu"
				"In7.Cu" "In8.Cu" "In9.Cu" "In10.Cu"
			)
			(hatch none 0.5)
			(connect_pads
				(clearance 0)
			)
			(min_thickness 0.25)
			(keepout
				(tracks not_allowed)
				(vias allowed)
				(pads allowed)
				(copperpour not_allowed)
				(footprints allowed)
			)
			(placement
				(enabled no)
				(sheetname "")
			)
			(fill
				(thermal_gap 0.5)
				(thermal_bridge_width 0.5)
				(island_removal_mode 0)
			)
			(polygon
				(pts
					(arc
						(start 37.3888 -17.24025)
						(mid 35.7632 -17.24025)
						(end 37.3888 -17.24025)
					)
				)
			)
		)
	)
)
